# Data Center RDIMM DDR4 Tester — footprint library table
(fp_lib_table
  (lib (name "data-center-rdimm-ddr4-tester-footprints")(type "KiCad")(uri "${KIPRJMOD}/lib/data-center-rdimm-ddr4-tester-footprints")(options "")(descr ""))
)
